(kicad_pcb
	(version 20260206)
	(generator "pcbnew")
	(generator_version "10.0")
	(general
		(thickness 1.6)
		(legacy_teardrops no)
	)
	(paper "A4")
	(title_block
		(title "netronome-mezz — pcbd0082-001_rev01_jul9_a.brd")
		(comment 1 "Open CloudServer (Microsoft) / footprints 687-697 of 714")
	)
	(layers
		(0 "F.Cu" signal "TOP")
		(4 "In1.Cu" signal "02_GND")
		(6 "In2.Cu" signal "03_SIG")
		(8 "In3.Cu" signal "04_SIG")
		(10 "In4.Cu" signal "05_GND")
		(12 "In5.Cu" signal "06_PWR1")
		(14 "In6.Cu" signal "07_SIG")
		(16 "In7.Cu" signal "08_SIG")
		(18 "In8.Cu" signal "09_GND")
		(2 "B.Cu" signal "BOTTOM")
		(9 "F.Adhes" user "F.Adhesive")
		(11 "B.Adhes" user "B.Adhesive")
		(13 "F.Paste" user "Package Geometry/Pastemask Top")
		(15 "B.Paste" user "Package Geometry/Pastemask Bottom")
		(5 "F.SilkS" user "Ref Des/Silkscreen Top")
		(7 "B.SilkS" user "Ref Des/Silkscreen Bottom")
		(1 "F.Mask" user "Board Geometry/Soldermask Top")
		(3 "B.Mask" user "Board Geometry/Soldermask Bottom")
		(17 "Dwgs.User" user "User.Drawings")
		(19 "Cmts.User" user "User.Comments")
		(21 "Eco1.User" user "User.Eco1")
		(23 "Eco2.User" user "User.Eco2")
		(25 "Edge.Cuts" user "Board Geometry/Outline")
		(27 "Margin" user)
		(31 "F.CrtYd" user "Package Geometry/Place Bound Top")
		(29 "B.CrtYd" user "Package Geometry/Place Bound Bottom")
		(35 "F.Fab" user "Ref Des/Assembly Top")
		(33 "B.Fab" user "Ref Des/Assembly Bottom")
		(45 "User.4" user "COMPVAL_TYPE_BOTTOM")
	)
	(footprint ""
		(layer "B.Cu")
		(at 53.237003 19.541998 180)
		(property "Reference" "C44"
			(at 0.050673 -2.556002 270)
			(unlocked yes)
			(layer "B.SilkS")
			(effects
				(font
					(size 0.7874 0.5842)
					(thickness 0.127)
				)
				(justify mirror)
			)
		)
		(property "Value" ""
			(at 0 0 0)
			(layer "B.Fab")
			(effects
				(font
					(size 1.27 1.27)
				)
				(justify mirror)
			)
		)
		(duplicate_pad_numbers_are_jumpers no)
		(fp_circle
			(center 0 0)
			(end -0.104648 0)
			(stroke
				(width 0.1016)
				(type default)
			)
			(fill no)
			(layer "B.SilkS")
		)
		(fp_poly
			(pts
				(xy 0.381 -0.889) (xy 0.381 0.889) (xy -0.381 0.889) (xy -0.381 -0.889)
			)
			(stroke
				(width 0)
				(type default)
			)
			(fill no)
			(layer "B.CrtYd")
		)
		(fp_line
			(start 0.508 1.016)
			(end 0.508 -1.016)
			(stroke
				(width 0.0254)
				(type default)
			)
			(layer "B.Fab")
		)
		(fp_line
			(start 0.508 -1.016)
			(end 0.254 -1.016)
			(stroke
				(width 0.0254)
				(type default)
			)
			(layer "B.Fab")
		)
		(fp_line
			(start 0.254 -1.016)
			(end -0.508 -1.016)
			(stroke
				(width 0.0254)
				(type default)
			)
			(layer "B.Fab")
		)
		(fp_line
			(start -0.508 1.016)
			(end 0.508 1.016)
			(stroke
				(width 0.0254)
				(type default)
			)
			(layer "B.Fab")
		)
		(fp_line
			(start -0.508 -1.016)
			(end -0.508 1.016)
			(stroke
				(width 0.0254)
				(type default)
			)
			(layer "B.Fab")
		)
		(pad "1" smd custom
			(at 0 -0.500126)
			(size 0.127 0.127)
			(layers "B.Cu" "B.Mask" "B.Paste")
			(net "VDDA_DDR0_32A")
			(options
				(clearance outline)
				(anchor circle)
			)
			(primitives
				(gr_poly
					(pts
						(xy -0.1778 0.254) (xy 0.1778 0.254) (xy 0.254 0.1778) (xy 0.254 -0.1778) (xy 0.1778 -0.254) (xy -0.1778 -0.254)
						(xy -0.254 -0.1778) (xy -0.254 0.1778)
					)
					(width 0)
					(fill yes)
				)
			)
		)
		(pad "2" smd custom
			(at 0 0.500126)
			(size 0.127 0.127)
			(layers "B.Cu" "B.Mask" "B.Paste")
			(net "GND")
			(options
				(clearance outline)
				(anchor circle)
			)
			(primitives
				(gr_poly
					(pts
						(xy -0.1778 0.254) (xy 0.1778 0.254) (xy 0.254 0.1778) (xy 0.254 -0.1778) (xy 0.1778 -0.254) (xy -0.1778 -0.254)
						(xy -0.254 -0.1778) (xy -0.254 0.1778)
					)
					(width 0)
					(fill yes)
				)
			)
		)
	)
	(footprint ""
		(layer "B.Cu")
		(at 79.450997 25.813004)
		(property "Reference" "V3_A-CAS"
			(at 0 0 0)
			(layer "B.SilkS")
			(hide yes)
			(effects
				(font
					(size 1.27 1.27)
				)
				(justify mirror)
			)
		)
		(property "Value" ""
			(at 0 0 0)
			(layer "B.Fab")
			(effects
				(font
					(size 1.27 1.27)
				)
				(justify mirror)
			)
		)
		(duplicate_pad_numbers_are_jumpers no)
		(pad "1" thru_hole circle
			(at 0 0 180)
			(size 0.4572 0.4572)
			(drill 0.20574)
			(layers "*.Cu" "*.Mask")
			(remove_unused_layers no)
			(net "DDR0_32A_CAS_L")
			(clearance 0.1143)
			(thermal_gap 0.1143)
		)
	)
	(footprint ""
		(layer "B.Cu")
		(at 80.250995 6.698996)
		(property "Reference" "V1_A-A10"
			(at 0 0 0)
			(layer "B.SilkS")
			(hide yes)
			(effects
				(font
					(size 1.27 1.27)
				)
				(justify mirror)
			)
		)
		(property "Value" ""
			(at 0 0 0)
			(layer "B.Fab")
			(effects
				(font
					(size 1.27 1.27)
				)
				(justify mirror)
			)
		)
		(duplicate_pad_numbers_are_jumpers no)
		(pad "1" thru_hole circle
			(at 0 0 180)
			(size 0.4572 0.4572)
			(drill 0.20574)
			(layers "*.Cu" "*.Mask")
			(remove_unused_layers no)
			(net "DDR0_32A_A10")
			(clearance 0.1143)
			(thermal_gap 0.1143)
		)
	)
	(footprint ""
		(layer "B.Cu")
		(at 82.65099 13.456006)
		(property "Reference" "V2_A-A05"
			(at 0 0 0)
			(layer "B.SilkS")
			(hide yes)
			(effects
				(font
					(size 1.27 1.27)
				)
				(justify mirror)
			)
		)
		(property "Value" ""
			(at 0 0 0)
			(layer "B.Fab")
			(effects
				(font
					(size 1.27 1.27)
				)
				(justify mirror)
			)
		)
		(duplicate_pad_numbers_are_jumpers no)
		(pad "1" thru_hole circle
			(at 0 0 180)
			(size 0.4572 0.4572)
			(drill 0.20574)
			(layers "*.Cu" "*.Mask")
			(remove_unused_layers no)
			(net "DDR0_32A_A5")
			(clearance 0.1143)
			(thermal_gap 0.1143)
		)
	)
	(footprint ""
		(layer "B.Cu")
		(at 62.357 6.604 90)
		(property "Reference" "C278"
			(at -0.02667 4.318 0)
			(unlocked yes)
			(layer "B.SilkS")
			(effects
				(font
					(size 0.7874 0.5842)
					(thickness 0.127)
				)
				(justify left mirror)
			)
		)
		(property "Value" "22UF"
			(at 0.148158 1.7526 0)
			(unlocked yes)
			(layer "B.Fab")
			(hide yes)
			(effects
				(font
					(size 1.27 0.9652)
					(thickness 0.000001)
				)
				(justify left mirror)
			)
		)
		(property "Device Type" "CAPC0063"
			(at 0.148158 1.7526 0)
			(unlocked yes)
			(layer "B.Fab")
			(hide yes)
			(effects
				(font
					(size 1.27 0.9652)
					(thickness 0.000001)
				)
				(justify left mirror)
			)
		)
		(duplicate_pad_numbers_are_jumpers no)
		(fp_circle
			(center 0 0)
			(end 0 0.127)
			(stroke
				(width 0.2032)
				(type default)
			)
			(fill no)
			(layer "B.SilkS")
		)
		(fp_poly
			(pts
				(xy -0.7874 -1.6637) (xy 0.7874 -1.6637) (xy 0.7874 1.6637) (xy -0.7874 1.6637)
			)
			(stroke
				(width 0)
				(type default)
			)
			(fill no)
			(layer "B.CrtYd")
		)
		(fp_line
			(start 0.4064 -0.7874)
			(end -0.4064 -0.7874)
			(stroke
				(width 0.0254)
				(type default)
			)
			(layer "B.Fab")
		)
		(fp_line
			(start -0.4064 -0.7874)
			(end -0.4064 0.8128)
			(stroke
				(width 0.0254)
				(type default)
			)
			(layer "B.Fab")
		)
		(fp_line
			(start 0.4064 0.8128)
			(end 0.4064 -0.7874)
			(stroke
				(width 0.0254)
				(type default)
			)
			(layer "B.Fab")
		)
		(fp_line
			(start -0.4064 0.8128)
			(end 0.4064 0.8128)
			(stroke
				(width 0.0254)
				(type default)
			)
			(layer "B.Fab")
		)
		(pad "1" smd rect
			(at 0 -0.8001 270)
			(size 0.8636 0.9652)
			(layers "B.Cu" "B.Mask" "B.Paste")
			(net "VDDA_PCIE0")
		)
		(pad "2" smd rect
			(at 0 0.8001 270)
			(size 0.8636 0.9652)
			(layers "B.Cu" "B.Mask" "B.Paste")
			(net "GND")
		)
		(zone
			(layer "B.Cu")
			(hatch none 0.5)
			(connect_pads
				(clearance 0)
			)
			(min_thickness 0.25)
			(keepout
				(tracks not_allowed)
				(vias allowed)
				(pads allowed)
				(copperpour not_allowed)
				(footprints allowed)
			)
			(placement
				(enabled no)
				(sheetname "")
			)
			(fill
				(thermal_gap 0.5)
				(thermal_bridge_width 0.5)
				(island_removal_mode 0)
			)
			(polygon
				(pts
					(xy 62.103 6.5405) (xy 62.103 6.6675) (xy 62.611 6.6675) (xy 62.611 6.5405)
				)
			)
		)
	)
	(footprint ""
		(layer "B.Cu")
		(at 77.051002 29.812996)
		(property "Reference" "V_A-CB1"
			(at 0 0 0)
			(layer "B.SilkS")
			(hide yes)
			(effects
				(font
					(size 1.27 1.27)
				)
				(justify mirror)
			)
		)
		(property "Value" ""
			(at 0 0 0)
			(layer "B.Fab")
			(effects
				(font
					(size 1.27 1.27)
				)
				(justify mirror)
			)
		)
		(duplicate_pad_numbers_are_jumpers no)
		(pad "1" thru_hole circle
			(at 0 0 180)
			(size 0.4572 0.4572)
			(drill 0.20574)
			(layers "*.Cu" "*.Mask")
			(remove_unused_layers no)
			(net "DDR0_32A_CB1")
			(clearance 0.1143)
			(thermal_gap 0.1143)
		)
	)
	(footprint ""
		(layer "B.Cu")
		(at 61.736986 22.041993 90)
		(property "Reference" "R187"
			(at 0 0 90)
			(layer "B.SilkS")
			(hide yes)
			(effects
				(font
					(size 1.27 1.27)
				)
				(justify mirror)
			)
		)
		(property "Value" ""
			(at 0 0 90)
			(layer "B.Fab")
			(effects
				(font
					(size 1.27 1.27)
				)
				(justify mirror)
			)
		)
		(duplicate_pad_numbers_are_jumpers no)
		(fp_circle
			(center 0 0)
			(end 0 0.104648)
			(stroke
				(width 0.1016)
				(type default)
			)
			(fill no)
			(layer "B.SilkS")
		)
		(fp_poly
			(pts
				(xy 0.381 -0.889) (xy 0.381 0.889) (xy -0.381 0.889) (xy -0.381 -0.889)
			)
			(stroke
				(width 0)
				(type default)
			)
			(fill no)
			(layer "B.CrtYd")
		)
		(fp_line
			(start 0.508 -1.016)
			(end 0.254 -1.016)
			(stroke
				(width 0.0254)
				(type default)
			)
			(layer "B.Fab")
		)
		(fp_line
			(start 0.254 -1.016)
			(end -0.508 -1.016)
			(stroke
				(width 0.0254)
				(type default)
			)
			(layer "B.Fab")
		)
		(fp_line
			(start -0.508 -1.016)
			(end -0.508 1.016)
			(stroke
				(width 0.0254)
				(type default)
			)
			(layer "B.Fab")
		)
		(fp_line
			(start 0.508 1.016)
			(end 0.508 -1.016)
			(stroke
				(width 0.0254)
				(type default)
			)
			(layer "B.Fab")
		)
		(fp_line
			(start -0.508 1.016)
			(end 0.508 1.016)
			(stroke
				(width 0.0254)
				(type default)
			)
			(layer "B.Fab")
		)
		(pad "1" smd custom
			(at 0 -0.500126 270)
			(size 0.127 0.127)
			(layers "B.Cu" "B.Mask" "B.Paste")
			(net "GND")
			(options
				(clearance outline)
				(anchor circle)
			)
			(primitives
				(gr_poly
					(pts
						(xy -0.1778 0.254) (xy 0.1778 0.254) (xy 0.254 0.1778) (xy 0.254 -0.1778) (xy 0.1778 -0.254) (xy -0.1778 -0.254)
						(xy -0.254 -0.1778) (xy -0.254 0.1778)
					)
					(width 0)
					(fill yes)
				)
			)
		)
		(pad "2" smd custom
			(at 0 0.500126 270)
			(size 0.127 0.127)
			(layers "B.Cu" "B.Mask" "B.Paste")
			(net "A_DZQ0")
			(options
				(clearance outline)
				(anchor circle)
			)
			(primitives
				(gr_poly
					(pts
						(xy -0.1778 0.254) (xy 0.1778 0.254) (xy 0.254 0.1778) (xy 0.254 -0.1778) (xy 0.1778 -0.254) (xy -0.1778 -0.254)
						(xy -0.254 -0.1778) (xy -0.254 0.1778)
					)
					(width 0)
					(fill yes)
				)
			)
		)
	)
	(footprint ""
		(layer "B.Cu")
		(at 21.336 13.589)
		(property "Reference" "R30"
			(at -0.15367 -0.889 270)
			(unlocked yes)
			(layer "B.SilkS")
			(effects
				(font
					(size 0.7874 0.5842)
					(thickness 0.127)
				)
				(justify left mirror)
			)
		)
		(property "Value" "4.75K"
			(at 0.148158 1.3462 270)
			(unlocked yes)
			(layer "B.Fab")
			(hide yes)
			(effects
				(font
					(size 1.27 0.9652)
					(thickness 0.000001)
				)
				(justify left mirror)
			)
		)
		(property "Device Type" "REST4024"
			(at 0.148158 1.3462 270)
			(unlocked yes)
			(layer "B.Fab")
			(hide yes)
			(effects
				(font
					(size 1.27 0.9652)
					(thickness 0.000001)
				)
				(justify left mirror)
			)
		)
		(duplicate_pad_numbers_are_jumpers no)
		(fp_poly
			(pts
				(xy -0.635 1.0668) (xy -0.635 -1.0668) (xy 0.635 -1.0668) (xy 0.635 1.0668)
			)
			(stroke
				(width 0)
				(type default)
			)
			(fill no)
			(layer "B.CrtYd")
		)
		(fp_line
			(start -0.254 -0.508)
			(end -0.254 0.508)
			(stroke
				(width 0.0254)
				(type default)
			)
			(layer "B.Fab")
		)
		(fp_line
			(start -0.254 0.508)
			(end 0.254 0.508)
			(stroke
				(width 0.0254)
				(type default)
			)
			(layer "B.Fab")
		)
		(fp_line
			(start 0.254 -0.508)
			(end -0.254 -0.508)
			(stroke
				(width 0.0254)
				(type default)
			)
			(layer "B.Fab")
		)
		(fp_line
			(start 0.254 0.508)
			(end 0.254 -0.508)
			(stroke
				(width 0.0254)
				(type default)
			)
			(layer "B.Fab")
		)
		(pad "1" smd rect
			(at 0 -0.4191 180)
			(size 0.508 0.5334)
			(layers "B.Cu" "B.Mask" "B.Paste")
			(net "VDD_3.3V")
		)
		(pad "2" smd rect
			(at 0 0.4191 180)
			(size 0.508 0.5334)
			(layers "B.Cu" "B.Mask" "B.Paste")
			(net "NFP_CFG_SPI_FLASH_SEL")
		)
		(zone
			(layer "B.Cu")
			(hatch none 0.5)
			(connect_pads
				(clearance 0)
			)
			(min_thickness 0.25)
			(keepout
				(tracks not_allowed)
				(vias allowed)
				(pads allowed)
				(copperpour not_allowed)
				(footprints allowed)
			)
			(placement
				(enabled no)
				(sheetname "")
			)
			(fill
				(thermal_gap 0.5)
				(thermal_bridge_width 0.5)
				(island_removal_mode 0)
			)
			(polygon
				(pts
					(xy 21.3106 13.5636) (xy 21.3106 13.6144) (xy 21.3614 13.6144) (xy 21.3614 13.5636)
				)
			)
		)
	)
	(footprint ""
		(layer "B.Cu")
		(at 30.099 32.639)
		(property "Reference" "R95"
			(at -0.02667 3.683 270)
			(unlocked yes)
			(layer "B.SilkS")
			(effects
				(font
					(size 0.7874 0.5842)
					(thickness 0.127)
				)
				(justify left mirror)
			)
		)
		(property "Value" "4.75K"
			(at 0.148158 1.3462 270)
			(unlocked yes)
			(layer "B.Fab")
			(hide yes)
			(effects
				(font
					(size 1.27 0.9652)
					(thickness 0.000001)
				)
				(justify left mirror)
			)
		)
		(property "Device Type" "REST4024"
			(at 0.148158 1.3462 270)
			(unlocked yes)
			(layer "B.Fab")
			(hide yes)
			(effects
				(font
					(size 1.27 0.9652)
					(thickness 0.000001)
				)
				(justify left mirror)
			)
		)
		(duplicate_pad_numbers_are_jumpers no)
		(fp_poly
			(pts
				(xy -0.635 1.0668) (xy -0.635 -1.0668) (xy 0.635 -1.0668) (xy 0.635 1.0668)
			)
			(stroke
				(width 0)
				(type default)
			)
			(fill no)
			(layer "B.CrtYd")
		)
		(fp_line
			(start -0.254 -0.508)
			(end -0.254 0.508)
			(stroke
				(width 0.0254)
				(type default)
			)
			(layer "B.Fab")
		)
		(fp_line
			(start -0.254 0.508)
			(end 0.254 0.508)
			(stroke
				(width 0.0254)
				(type default)
			)
			(layer "B.Fab")
		)
		(fp_line
			(start 0.254 -0.508)
			(end -0.254 -0.508)
			(stroke
				(width 0.0254)
				(type default)
			)
			(layer "B.Fab")
		)
		(fp_line
			(start 0.254 0.508)
			(end 0.254 -0.508)
			(stroke
				(width 0.0254)
				(type default)
			)
			(layer "B.Fab")
		)
		(pad "1" smd rect
			(at 0 -0.4191 180)
			(size 0.508 0.5334)
			(layers "B.Cu" "B.Mask" "B.Paste")
			(net "GND")
		)
		(pad "2" smd rect
			(at 0 0.4191 180)
			(size 0.508 0.5334)
			(layers "B.Cu" "B.Mask" "B.Paste")
			(net "_NFP_CORE_VID3")
		)
		(zone
			(layer "B.Cu")
			(hatch none 0.5)
			(connect_pads
				(clearance 0)
			)
			(min_thickness 0.25)
			(keepout
				(tracks not_allowed)
				(vias allowed)
				(pads allowed)
				(copperpour not_allowed)
				(footprints allowed)
			)
			(placement
				(enabled no)
				(sheetname "")
			)
			(fill
				(thermal_gap 0.5)
				(thermal_bridge_width 0.5)
				(island_removal_mode 0)
			)
			(polygon
				(pts
					(xy 30.0736 32.6136) (xy 30.0736 32.6644) (xy 30.1244 32.6644) (xy 30.1244 32.6136)
				)
			)
		)
	)
	(footprint ""
		(layer "B.Cu")
		(at 81.1022 42.799 90)
		(property "Reference" "C128"
			(at -0.78867 1.3208 0)
			(unlocked yes)
			(layer "B.SilkS")
			(effects
				(font
					(size 0.7874 0.5842)
					(thickness 0.127)
				)
				(justify left mirror)
			)
		)
		(property "Value" "0.1UF"
			(at 0.091846 0.2921 0)
			(unlocked yes)
			(layer "B.Fab")
			(hide yes)
			(effects
				(font
					(size 0.7874 0.5842)
					(thickness 0.2032)
				)
				(justify left mirror)
			)
		)
		(property "Device Type" "CAPC0073"
			(at 0.091846 0.2921 0)
			(unlocked yes)
			(layer "B.Fab")
			(hide yes)
			(effects
				(font
					(size 0.7874 0.5842)
					(thickness 0.2032)
				)
				(justify left mirror)
			)
		)
		(duplicate_pad_numbers_are_jumpers no)
		(fp_poly
			(pts
				(xy -0.635 1.0668) (xy -0.635 -1.0668) (xy 0.635 -1.0668) (xy 0.635 1.0668)
			)
			(stroke
				(width 0)
				(type default)
			)
			(fill no)
			(layer "B.CrtYd")
		)
		(fp_line
			(start 0.254 -0.508)
			(end -0.254 -0.508)
			(stroke
				(width 0.0254)
				(type default)
			)
			(layer "B.Fab")
		)
		(fp_line
			(start -0.254 -0.508)
			(end -0.254 0.508)
			(stroke
				(width 0.0254)
				(type default)
			)
			(layer "B.Fab")
		)
		(fp_line
			(start 0.254 0.508)
			(end 0.254 -0.508)
			(stroke
				(width 0.0254)
				(type default)
			)
			(layer "B.Fab")
		)
		(fp_line
			(start -0.254 0.508)
			(end 0.254 0.508)
			(stroke
				(width 0.0254)
				(type default)
			)
			(layer "B.Fab")
		)
		(pad "1" smd rect
			(at 0 -0.4191 270)
			(size 0.508 0.5334)
			(layers "B.Cu" "B.Mask" "B.Paste")
			(net "11N2152")
		)
		(pad "2" smd rect
			(at 0 0.4191 270)
			(size 0.508 0.5334)
			(layers "B.Cu" "B.Mask" "B.Paste")
			(net "GND")
		)
		(zone
			(layer "B.Cu")
			(hatch none 0.5)
			(connect_pads
				(clearance 0)
			)
			(min_thickness 0.25)
			(keepout
				(tracks not_allowed)
				(vias allowed)
				(pads allowed)
				(copperpour not_allowed)
				(footprints allowed)
			)
			(placement
				(enabled no)
				(sheetname "")
			)
			(fill
				(thermal_gap 0.5)
				(thermal_bridge_width 0.5)
				(island_removal_mode 0)
			)
			(polygon
				(pts
					(xy 81.0768 42.8244) (xy 81.1276 42.8244) (xy 81.1276 42.7736) (xy 81.0768 42.7736)
				)
			)
		)
	)
	(footprint ""
		(layer "B.Cu")
		(at 51.737006 10.042017 90)
		(property "Reference" "C43"
			(at 0 0 90)
			(layer "B.SilkS")
			(hide yes)
			(effects
				(font
					(size 1.27 1.27)
				)
				(justify mirror)
			)
		)
		(property "Value" ""
			(at 0 0 90)
			(layer "B.Fab")
			(effects
				(font
					(size 1.27 1.27)
				)
				(justify mirror)
			)
		)
		(duplicate_pad_numbers_are_jumpers no)
		(fp_circle
			(center 0 0)
			(end 0 0.104648)
			(stroke
				(width 0.1016)
				(type default)
			)
			(fill no)
			(layer "B.SilkS")
		)
		(fp_poly
			(pts
				(xy 0.381 -0.889) (xy 0.381 0.889) (xy -0.381 0.889) (xy -0.381 -0.889)
			)
			(stroke
				(width 0)
				(type default)
			)
			(fill no)
			(layer "B.CrtYd")
		)
		(fp_line
			(start 0.508 -1.016)
			(end 0.254 -1.016)
			(stroke
				(width 0.0254)
				(type default)
			)
			(layer "B.Fab")
		)
		(fp_line
			(start 0.254 -1.016)
			(end -0.508 -1.016)
			(stroke
				(width 0.0254)
				(type default)
			)
			(layer "B.Fab")
		)
		(fp_line
			(start -0.508 -1.016)
			(end -0.508 1.016)
			(stroke
				(width 0.0254)
				(type default)
			)
			(layer "B.Fab")
		)
		(fp_line
			(start 0.508 1.016)
			(end 0.508 -1.016)
			(stroke
				(width 0.0254)
				(type default)
			)
			(layer "B.Fab")
		)
		(fp_line
			(start -0.508 1.016)
			(end 0.508 1.016)
			(stroke
				(width 0.0254)
				(type default)
			)
			(layer "B.Fab")
		)
		(pad "1" smd custom
			(at 0 -0.500126 270)
			(size 0.127 0.127)
			(layers "B.Cu" "B.Mask" "B.Paste")
			(net "VDDAH_SERDES")
			(options
				(clearance outline)
				(anchor circle)
			)
			(primitives
				(gr_poly
					(pts
						(xy -0.1778 0.254) (xy 0.1778 0.254) (xy 0.254 0.1778) (xy 0.254 -0.1778) (xy 0.1778 -0.254) (xy -0.1778 -0.254)
						(xy -0.254 -0.1778) (xy -0.254 0.1778)
					)
					(width 0)
					(fill yes)
				)
			)
		)
		(pad "2" smd custom
			(at 0 0.500126 270)
			(size 0.127 0.127)
			(layers "B.Cu" "B.Mask" "B.Paste")
			(net "GND")
			(options
				(clearance outline)
				(anchor circle)
			)
			(primitives
				(gr_poly
					(pts
						(xy -0.1778 0.254) (xy 0.1778 0.254) (xy 0.254 0.1778) (xy 0.254 -0.1778) (xy 0.1778 -0.254) (xy -0.1778 -0.254)
						(xy -0.254 -0.1778) (xy -0.254 0.1778)
					)
					(width 0)
					(fill yes)
				)
			)
		)
	)
)
